# BASEBOARD_FAB2 (Tioga Pass) — schematic netlist excerpt (pin names and nets, part order shuffled) for the footprints in the layout excerpt that follows; sources: Cadence DE-HDL packaged netlist, KiCad conversion of Wiwynn_Tioga_Pass_MB.brd

R9R6  RES  49.9 1% CHIP  pkg 0402  page 167 : A = ISENSE_TMP421_2_BC ; B = ISENSE_TMP421_2_DXN

Q1W1  FET_N  2N7002 FET  pkg SOT23LF  page 250
  GATE  = FM_OCP_MEZZA_PRES_N
  SRC  = GND
  DRN  = FM_OCP_MEZZA_PRES

(kicad_pcb
	(version 20260206)
	(generator "pcbnew")
	(generator_version "10.0")
	(general
		(thickness 1.6)
		(legacy_teardrops no)
	)
	(paper "A4")
	(title_block
		(title "Wiwynn_Tioga_Pass_MB.brd")
		(comment 1 "Tioga Pass / footprints 4040-4041 of 4770")
	)
	(layers
		(0 "F.Cu" signal "TOP")
		(4 "In1.Cu" signal "L2GND")
		(6 "In2.Cu" signal "L3")
		(8 "In3.Cu" signal "L4GND")
		(10 "In4.Cu" signal "L5")
		(12 "In5.Cu" signal "L6GND")
		(14 "In6.Cu" signal "L7VCC")
		(16 "In7.Cu" signal "L8VCC")
		(18 "In8.Cu" signal "L9GND")
		(20 "In9.Cu" signal "L10")
		(22 "In10.Cu" signal "L11GND")
		(24 "In11.Cu" signal "L12")
		(26 "In12.Cu" signal "L13GND")
		(2 "B.Cu" signal "BOTTOM")
		(9 "F.Adhes" user "F.Adhesive")
		(11 "B.Adhes" user "B.Adhesive")
		(13 "F.Paste" user "Package Geometry/Pastemask Top")
		(15 "B.Paste" user "Package Geometry/Pastemask Bottom")
		(5 "F.SilkS" user "Ref Des/Silkscreen Top")
		(7 "B.SilkS" user "Ref Des/Silkscreen Bottom")
		(1 "F.Mask" user "Board Geometry/Soldermask Top")
		(3 "B.Mask" user "Board Geometry/Soldermask Bottom")
		(17 "Dwgs.User" user "User.Drawings")
		(19 "Cmts.User" user "User.Comments")
		(21 "Eco1.User" user "User.Eco1")
		(23 "Eco2.User" user "User.Eco2")
		(25 "Edge.Cuts" user "Board Geometry/Outline")
		(27 "Margin" user)
		(31 "F.CrtYd" user "Package Geometry/Place Bound Top")
		(29 "B.CrtYd" user "Package Geometry/Place Bound Bottom")
		(35 "F.Fab" user "Ref Des/Assembly Top")
		(33 "B.Fab" user "Ref Des/Assembly Bottom")
	)
	(footprint ""
		(layer "B.Cu")
		(at 17.907 -46.482 -90)
		(property "Reference" "R9R6"
			(at 0 0 90)
			(layer "B.SilkS")
			(hide yes)
			(effects
				(font
					(size 1.27 1.27)
				)
				(justify mirror)
			)
		)
		(property "Value" ""
			(at 0 0 90)
			(layer "B.Fab")
			(effects
				(font
					(size 1.27 1.27)
				)
				(justify mirror)
			)
		)
		(duplicate_pad_numbers_are_jumpers no)
		(fp_poly
			(pts
				(xy 0.2794 -0.1016) (xy -0.2794 -0.1016) (xy -0.2794 0.9906) (xy 0.2794 0.9906)
			)
			(stroke
				(width 0)
				(type default)
			)
			(fill no)
			(layer "B.CrtYd")
		)
		(fp_line
			(start -0.2794 0.9906)
			(end -0.2794 -0.1016)
			(stroke
				(width 0.1)
				(type default)
			)
			(layer "B.Fab")
		)
		(fp_line
			(start 0.2794 0.9906)
			(end -0.2794 0.9906)
			(stroke
				(width 0.1)
				(type default)
			)
			(layer "B.Fab")
		)
		(fp_line
			(start -0.2794 -0.1016)
			(end 0.2794 -0.1016)
			(stroke
				(width 0.1)
				(type default)
			)
			(layer "B.Fab")
		)
		(fp_line
			(start 0.2794 -0.1016)
			(end 0.2794 0.9906)
			(stroke
				(width 0.1)
				(type default)
			)
			(layer "B.Fab")
		)
		(pad "1" smd rect
			(at 0 0 90)
			(size 0.508 0.508)
			(layers "B.Cu" "B.Mask" "B.Paste")
			(net "ISENSE_TMP421_2_BC")
		)
		(pad "2" smd rect
			(at 0 0.889 90)
			(size 0.508 0.508)
			(layers "B.Cu" "B.Mask" "B.Paste")
			(net "ISENSE_TMP421_2_DXN")
		)
		(zone
			(layer "B.Cu")
			(hatch none 0.5)
			(connect_pads
				(clearance 0)
			)
			(min_thickness 0.25)
			(keepout
				(tracks not_allowed)
				(vias allowed)
				(pads allowed)
				(copperpour not_allowed)
				(footprints allowed)
			)
			(placement
				(enabled no)
				(sheetname "")
			)
			(fill
				(thermal_gap 0.5)
				(thermal_bridge_width 0.5)
				(island_removal_mode 0)
			)
			(polygon
				(pts
					(xy 17.272 -46.228) (xy 17.272 -46.736) (xy 17.653 -46.736) (xy 17.653 -46.228)
				)
			)
		)
		(zone
			(layer "B.Cu")
			(hatch none 0.5)
			(connect_pads
				(clearance 0)
			)
			(min_thickness 0.25)
			(keepout
				(tracks allowed)
				(vias not_allowed)
				(pads allowed)
				(copperpour not_allowed)
				(footprints allowed)
			)
			(placement
				(enabled no)
				(sheetname "")
			)
			(fill
				(thermal_gap 0.5)
				(thermal_bridge_width 0.5)
				(island_removal_mode 0)
			)
			(polygon
				(pts
					(xy 17.653 -46.228) (xy 17.653 -46.736) (xy 17.272 -46.736) (xy 17.272 -46.228)
				)
			)
		)
	)
	(footprint ""
		(layer "B.Cu")
		(at 476.1865 -117.6655 90)
		(property "Reference" "Q1W1"
			(at 0.229362 -1.2065 90)
			(unlocked yes)
			(layer "B.SilkS")
			(effects
				(font
					(size 0.4064 0.254)
					(thickness 0.1524)
				)
				(justify left mirror)
			)
		)
		(property "Value" ""
			(at 0 0 90)
			(layer "B.Fab")
			(effects
				(font
					(size 1.27 1.27)
				)
				(justify mirror)
			)
		)
		(duplicate_pad_numbers_are_jumpers no)
		(fp_line
			(start -0.9525 -0.5715)
			(end -1.778 -0.5715)
			(stroke
				(width 0.1524)
				(type default)
			)
			(layer "B.SilkS")
		)
		(fp_line
			(start -1.778 -0.5715)
			(end -1.778 0.3175)
			(stroke
				(width 0.1524)
				(type default)
			)
			(layer "B.SilkS")
		)
		(fp_line
			(start -0.381 0.635)
			(end -0.381 1.27)
			(stroke
				(width 0.1524)
				(type default)
			)
			(layer "B.SilkS")
		)
		(fp_line
			(start -0.9525 2.4765)
			(end -1.778 2.4765)
			(stroke
				(width 0.1524)
				(type default)
			)
			(layer "B.SilkS")
		)
		(fp_line
			(start -1.778 2.4765)
			(end -1.778 1.5875)
			(stroke
				(width 0.1524)
				(type default)
			)
			(layer "B.SilkS")
		)
		(fp_circle
			(center 0.9525 -0.9271)
			(end 0.9525 -0.8001)
			(stroke
				(width 0.254)
				(type default)
			)
			(fill no)
			(layer "B.SilkS")
		)
		(fp_poly
			(pts
				(xy -1.778 2.4765) (xy -0.381 2.4765) (xy -0.381 -0.5715) (xy -1.778 -0.5715)
			)
			(stroke
				(width 0)
				(type default)
			)
			(fill no)
			(layer "B.CrtYd")
		)
		(fp_line
			(start -0.381 -0.5715)
			(end -0.381 2.4765)
			(stroke
				(width 0.1)
				(type default)
			)
			(layer "B.Fab")
		)
		(fp_line
			(start -1.778 -0.5715)
			(end -0.381 -0.5715)
			(stroke
				(width 0.1)
				(type default)
			)
			(layer "B.Fab")
		)
		(fp_line
			(start -0.381 2.4765)
			(end -1.778 2.4765)
			(stroke
				(width 0.1)
				(type default)
			)
			(layer "B.Fab")
		)
		(fp_line
			(start -1.778 2.4765)
			(end -1.778 -0.5715)
			(stroke
				(width 0.1)
				(type default)
			)
			(layer "B.Fab")
		)
		(fp_circle
			(center 0.9525 -0.9271)
			(end 0.9525 -0.8001)
			(stroke
				(width 0.254)
				(type default)
			)
			(fill no)
			(layer "B.Fab")
		)
		(pad "1" smd rect
			(at 0 0 270)
			(size 1.143 0.508)
			(layers "B.Cu" "B.Mask" "B.Paste")
			(net "FM_OCP_MEZZA_PRES_N")
		)
		(pad "2" smd rect
			(at 0 1.905 270)
			(size 1.143 0.508)
			(layers "B.Cu" "B.Mask" "B.Paste")
			(net "GND")
		)
		(pad "3" smd rect
			(at -2.159 0.9525 270)
			(size 1.143 0.508)
			(layers "B.Cu" "B.Mask" "B.Paste")
			(net "FM_OCP_MEZZA_PRES")
		)
	)
)
